5
5
4
4
3
3
2
2
1
1
D D
C C
B B
A A
POWER TRANSITION BOARD 
Pulling Out 
Detection 
LED TX: LED16 
LED RX:Q31 
Board To Wire Connection 4P20 CONN 
4x PWR/GND Pins 
20x Signals Pins 
36P24 Golden Finger 
36x PWR/GND Pins 
24x Signals Pins 
Slide Switch: SW1 
Green LED: LED1 
FCB 
Reserved I2C Buffer 
PCA9511 
Board To Board Connection 
DPB 
Title 
Size Document Number Rev
Date: Sheet 
of 
Lightning_PTB 
-1
BLOCK DIAGRAM 
A3 
1 5Thursday, March 09, 2017 
Wiwynn 
H/W R&D Dept. II 
8F,90,Sec. 1,Hsin Tai Wu Rd, 
Hsichih, Taipei Hsien 221, Taiwan, R.O.C
Title 
Size Document Number Rev
Date: Sheet 
of 
Lightning_PTB 
-1
BLOCK DIAGRAM 
A3 
1 5Thursday, March 09, 2017 
Wiwynn 
H/W R&D Dept. II 
8F,90,Sec. 1,Hsin Tai Wu Rd, 
Hsichih, Taipei Hsien 221, Taiwan, R.O.C
Title 
Size Document Number Rev
Date: Sheet 
of 
Lightning_PTB 
-1
BLOCK DIAGRAM 
A3 
1 5Thursday, March 09, 2017 
Wiwynn 
H/W R&D Dept. II 
8F,90,Sec. 1,Hsin Tai Wu Rd, 
Hsichih, Taipei Hsien 221, Taiwan, R.O.C



5
5
4
4
3
3
2
2
1
1
D D
C C
B B
A A
PIN Definition DY=Dummy parts 
  =not populated 
SCD1U10V2KX-5GP 
D1U = 0.1uF (2D2U means 2.2uF) 
10Voltage (6D3V means 6.3V) 
2 = size 0402, K tolerance 
K=tolerance 
[C code as below:] 
G=2% 
J=5% 
K=10% 
M=20% 
X=temp characteristics 
[C Series/Temp] 
N=NPO 
X=X7R/X5R 
Y=Y5V 
-5=different symbol/customer 
GP= Green Part (RoHS) 
562R2F- GP 
562 = 562 ohm, (2K2R means 2.2K ohm)
2 = size 0402 
F = 1% tolerance 
GP= Green Part (RoHS) 
RC size code as below: 
1 = 0201 
2= 0402 
3= 0603 
5= 0805 
6= 1206 
R tolerance code as below: 
D=0.5% 
F= 1% 
J= 5% 
Golden Finger 
To DPB 
4P20S 
To FCB 
Title 
Size Document Number Rev
Date: Sheet 
of 
Lightning_PTB 
-1
PIN Definition 
A3 
2 5Thursday, March 09, 2017 
Wiwynn 
H/W R&D Dept. II 
8F,90,Sec. 1,Hsin Tai Wu Rd, 
Hsichih, Taipei Hsien 221, Taiwan, R.O.C
Title 
Size Document Number Rev
Date: Sheet 
of 
Lightning_PTB 
-1
PIN Definition 
A3 
2 5Thursday, March 09, 2017 
Wiwynn 
H/W R&D Dept. II 
8F,90,Sec. 1,Hsin Tai Wu Rd, 
Hsichih, Taipei Hsien 221, Taiwan, R.O.C
Title 
Size Document Number Rev
Date: Sheet 
of 
Lightning_PTB 
-1
PIN Definition 
A3 
2 5Thursday, March 09, 2017 
Wiwynn 
H/W R&D Dept. II 
8F,90,Sec. 1,Hsin Tai Wu Rd, 
Hsichih, Taipei Hsien 221, Taiwan, R.O.C



5
5
4
4
3
3
2
2
1
1
D D
C C
B B
A A
I2C_C_BUFFER 
PULLING OUT DETECTION 
EMITTER DETECTOR 
"H"=Tray is "pulling out" 
"L"=Tray is "inside the chassis" 
FCB 
DPB DPB 
FCB 
I2C_C_BUF_SDAOUT 
I2C_C_BUF_EN 
I2C_C_BUF_SCLOUT 
EMITTER_K 
IR_switch_E 
TRAY_PRESENT_OUT_NET_B 
Tray present_OUT#_C 
I2C_C_BUF_SCLIN 
TRAY PRESENT_OUT_NET 
TRAY_MOSFET_G 
DETECTOR_C 
I2C_C_BUF_SDAIN 
I2C_C_BUF_READY 
P3V3 
P3V3 
P3V3 
P3V3 
P3V3 
P3V3 
P3V3 P5VA 
P3V3 
P3V3 
P3V3 
SELF_TRAY_PRESENT 4
I2C_C_SCL 4
I2C_C_BUF_SCL 4
I2C_C_SDA 4
I2C_C_BUF_SDA 4
Title 
Size Document Number Rev
Date: Sheet 
of 
Lightning_PTB 
-1
I2C_C BUFFER&PULLING OUT 
A3 
3 5Thursday, March 09, 2017 
Wiwynn 
H/W R&D Dept. II 
8F,90,Sec. 1,Hsin Tai Wu Rd, 
Hsichih, Taipei Hsien 221, Taiwan, R.O.C
Title 
Size Document Number Rev
Date: Sheet 
of 
Lightning_PTB 
-1
I2C_C BUFFER&PULLING OUT 
A3 
3 5Thursday, March 09, 2017 
Wiwynn 
H/W R&D Dept. II 
8F,90,Sec. 1,Hsin Tai Wu Rd, 
Hsichih, Taipei Hsien 221, Taiwan, R.O.C
Title 
Size Document Number Rev
Date: Sheet 
of 
Lightning_PTB 
-1
I2C_C BUFFER&PULLING OUT 
A3 
3 5Thursday, March 09, 2017 
Wiwynn 
H/W R&D Dept. II 
8F,90,Sec. 1,Hsin Tai Wu Rd, 
Hsichih, Taipei Hsien 221, Taiwan, R.O.C
R487 
0R2J-2-GP 
NOPOP 
1 2
R486 
0R2J-2-GP 
NOPOP 
1 2
R481 
0R2J-2-GP 
1 2
R369 
4K7R2J-2-GP 
NOPOP 
1 2
R344 
10KR2F-2-GP 
1 2
Q31 
SENSOR-2P-GP-U 
EC
R353 
10KR2F-2-GP 
1 2
PR65 
0R3J-0-U-GP 
1 2
Q33 
MMBT2222A-3-GP 
C
B
E
R370 
4K7R2J-2-GP 
NOPOP 
1 2
PR64 
0R3J-0-U-GP 
NOPOP 
1 2
LED16 
LED-IR-1-GP 
A K
C345 
SCD01U50V2KX-1GP 
1 2
R342 
10KR2F-2-GP 
1 2
R376 
100KR2F-L1-GP 
1 2
R374 
470KR2F-GP 
1 2
TP9 
TPAD32-GP 
1
U51 
PCA9511ADP-T-GP 
ENABLE 1
SCLOUT 2
SCLIN 3
GND 4 READY 5SDAIN 6SDAOUT 7VCC 8
R365 
0R2J-2-GP 
NOPOP 
1 2
R379 
10KR2F-2-GP 
1 2
R485 
0R2J-2-GP 
NOPOP 
1 2
R482 
0R2J-2-GP 
1 2
R366 
0R2J-2-GP 
1 2
R378 
68R5J-GP 
1 2
Q34 
2N7002-11-GP 
G
SD
R480 
0R2J-2-GP 
1 2
C344 
SCD1U50V3KX-GP 
1 2
R343 
10KR2F-2-GP 
1 2
R375 
100R2F-L1-GP-U 
1 2
R484 
0R2J-2-GP 
NOPOP 
1 2



5
5
4
4
3
3
2
2
1
1
D D
C C
B B
A A
4P20S PWR CONN 
SCREW HOLDs 
GOLDEN_FINGER 
PWM_EXP_B_OUT PWM_EXP_B 
SELF_1B&2B_HB 
PEER_TRAY_PRESENT 
TRAY_ID 
TRAY_ID 
SD_LATCH_RELEASE 
PEER_1A&2A_HB 
FCB_HW_REV 
SELF_1A&2A_HB 
SELF_1B&2B_HB 
PWM_EXP_B 
STRADDLE_I2C_C_SDA 
PWM_EXP_A 
TPS2490_LED 
PEER_1B&2B_HB 
SD_LATCH_RELEASE 
PEER_1A&2A_HB 
FCB_HW_REV 
PEER_TRAY_PRESENT PEER_1B&2B_HB 
PWM_EXP_A 
SELF_1A&2A_HB 
STRADDLE_I2C_C_SCL 
I2C_C_BUF_SDA_CONN 
PWM_EXP_A_OUT 
I2C_C_BUF_SDA_CONN 
I2C_C_BUF_SCL_CONN 
TPS2490_DISABLE 
I2C_C_BUF_SCL_CONN TPS2490_EN2 
TPS2490_EN1 
P12V 
P12V 
P12V 
P3V3 
P12V 
P5VA 
P12V 
I2C_C_BUF_SCL 3
SELF_TRAY_PRESENT 3
SELF_TRAY_PRESENT 3
I2C_C_SCL 3
I2C_C_SDA 3
I2C_C_BUF_SDA 3
Title 
Size Document Number Rev
Date: Sheet 
of 
Lightning_PTB 
-1
CONNs 
A3 
4 5Thursday, March 09, 2017 
Wiwynn 
H/W R&D Dept. II 
8F,90,Sec. 1,Hsin Tai Wu Rd, 
Hsichih, Taipei Hsien 221, Taiwan, R.O.C
Title 
Size Document Number Rev
Date: Sheet 
of 
Lightning_PTB 
-1
CONNs 
A3 
4 5Thursday, March 09, 2017 
Wiwynn 
H/W R&D Dept. II 
8F,90,Sec. 1,Hsin Tai Wu Rd, 
Hsichih, Taipei Hsien 221, Taiwan, R.O.C
Title 
Size Document Number Rev
Date: Sheet 
of 
Lightning_PTB 
-1
CONNs 
A3 
4 5Thursday, March 09, 2017 
Wiwynn 
H/W R&D Dept. II 
8F,90,Sec. 1,Hsin Tai Wu Rd, 
Hsichih, Taipei Hsien 221, Taiwan, R.O.C
C364 
SC47U16V0MX-GP 
NOPOP 
1 2
R386 0R2J-2-GP 1 2
LED1 
LED-G-203-GP 
A K
C359 
SC220P50V3JN-GP 
NOPOP 
1 2
SW1 
SW-PUSH-3P-3-GP 
1
2
3
4
5
R387 0R2J-2-GP 1 2
R388 0R2J-2-GP 1 2
02 Do not mirror 
TOP BOTTOM 
GF1 
GF-36P-24P-GP 
P18 P18 P17 P17 
P16 P16 P15 P15 P14 P14 P13 P13 
P12 P12 P11 P11 P10 P10 P9 P9 
P8 P8 P7 P7 P6 P6 P5 P5 
P4 P4 P3 P3 P2 P2 P1 P1 
P25 P25 P26 P26 P27 P27 P28 P28 
P29 P29 
P19 P19 P20 P20 
P21 P21 P22 P22 P23 P23 P24 P24 
S1 S1 
S2 S2 
S3 S3 
S4 S4 
S5 S5 
S6 S6 
S7 S7 
S8 S8 
S9 S9 
S10 S10 
S11 S11 
S12 S12 
S24 S24 
S23 S23 
S22 S22 
S21 S21 
S20 S20 
S19 S19 
S18 S18 
S17 S17 
S16 S16 
S15 S15 
S14 S14 
S13 S13 
P32 P32 
P31 P31 
P30 P30 
P36 P36 
P35 P35 
P34 P34 
P33 P33 
TC4 
ST68U16VDM-1-GP 
1 2
C349 
SC10U25V5KX-GP 
1 2
CN4 
FCI-CONN52-4R-GP 
P1_1 
P1_2 P1_3 
P1_5 
P1_6 P1_7 
P1_8 
P2_1 
P2_2 P2_3 
P2_4 
P2_5 
P2_6 P2_7 
P2_8 
NP1 
NP2 
P3_2 
P3_1 
P3_5 
P3_6 
P3_3 
P3_4 
P3_8 
P3_7 
P4_2 
P4_1 
P4_5 
P4_6 
P4_3 
P4_4 
P4_8 
P4_7 
A1 
B1 C1 
D1 
A2 
B2 C2 
D2 
P1_4 
A3 
A4 
A5 
B3 
B4 
B5 
C3 
C4 
C5 
D3 
D4 
D5 
R384 0R2J-2-GP 1 2
TC5 
ST68U16VDM-1-GP 
1 2
H1 
HOLE 
1
R391 
0R2J-2-GP 
1 2
R483 
2KR3F-L-GP 
1 2
H2 
HOLE 
1
C357 
SC220P50V3JN-GP 
NOPOP 
1 2
H3 
HOLE 
1
C358 
SC220P50V3JN-GP 
NOPOP 
1 2
C348 
SC10U25V5KX-GP 
1 2
H4 
HOLE 
1
C361 
SC47U16V0MX-GP 
NOPOP 
1 2
TC3 
ST68U16VDM-1-GP 
1 2
R389 0R2J-2-GP 1 2
R385 0R2J-2-GP 1 2
C362 
SC47U16V0MX-GP 
NOPOP 
1 2
C355 
SC10U25V5KX-GP 
1 2
R390 
0R2J-2-GP 
1 2
C363 
SC47U16V0MX-GP 
NOPOP 
1 2
C360 
SC220P50V3JN-GP 
NOPOP 
1 2



5
5
4
4
3
3
2
2
1
1
D D
C C
B B
A A
BLANK 
Title 
Size Document Number Rev
Date: Sheet 
of 
Lightning_PTB 
-1
BLANK 
A3 
5 5Thursday, March 09, 2017 
Wiwynn 
H/W R&D Dept. II 
8F,90,Sec. 1,Hsin Tai Wu Rd, 
Hsichih, Taipei Hsien 221, Taiwan, R.O.C
Title 
Size Document Number Rev
Date: Sheet 
of 
Lightning_PTB 
-1
BLANK 
A3 
5 5Thursday, March 09, 2017 
Wiwynn 
H/W R&D Dept. II 
8F,90,Sec. 1,Hsin Tai Wu Rd, 
Hsichih, Taipei Hsien 221, Taiwan, R.O.C
Title 
Size Document Number Rev
Date: Sheet 
of 
Lightning_PTB 
-1
BLANK 
A3 
5 5Thursday, March 09, 2017 
Wiwynn 
H/W R&D Dept. II 
8F,90,Sec. 1,Hsin Tai Wu Rd, 
Hsichih, Taipei Hsien 221, Taiwan, R.O.C